(kicad_pcb
	(version 20260206)
	(generator "pcbnew")
	(generator_version "10.0")
	(general
		(thickness 1.6)
		(legacy_teardrops no)
	)
	(paper "A4")
	(title_block
		(title "01162023_DA0F0TEBIF0_F0T_Expander_BD_F_brd_V02_OCP.brd")
		(comment 1 "Grand Teton / footprints 2344-2349 of 9728")
	)
	(layers
		(0 "F.Cu" signal "TOP")
		(4 "In1.Cu" signal "GND")
		(6 "In2.Cu" signal "VCC")
		(8 "In3.Cu" signal "VCC1")
		(10 "In4.Cu" signal "GND1")
		(12 "In5.Cu" signal "IN1")
		(14 "In6.Cu" signal "GND2")
		(16 "In7.Cu" signal "IN2")
		(18 "In8.Cu" signal "GND3")
		(20 "In9.Cu" signal "IN3")
		(22 "In10.Cu" signal "GND4")
		(24 "In11.Cu" signal "IN4")
		(26 "In12.Cu" signal "GND5")
		(28 "In13.Cu" signal "IN5")
		(30 "In14.Cu" signal "GND6")
		(32 "In15.Cu" signal "IN6")
		(34 "In16.Cu" signal "GND7")
		(2 "B.Cu" signal "BOTTOM")
		(9 "F.Adhes" user "F.Adhesive")
		(11 "B.Adhes" user "B.Adhesive")
		(13 "F.Paste" user "Package Geometry/Pastemask Top")
		(15 "B.Paste" user "Package Geometry/Pastemask Bottom")
		(5 "F.SilkS" user "Ref Des/Silkscreen Top")
		(7 "B.SilkS" user "Ref Des/Silkscreen Bottom")
		(1 "F.Mask" user "Board Geometry/Soldermask Top")
		(3 "B.Mask" user "Board Geometry/Soldermask Bottom")
		(17 "Dwgs.User" user "User.Drawings")
		(19 "Cmts.User" user "User.Comments")
		(21 "Eco1.User" user "User.Eco1")
		(23 "Eco2.User" user "User.Eco2")
		(25 "Edge.Cuts" user "Board Geometry/Outline")
		(27 "Margin" user)
		(31 "F.CrtYd" user "Package Geometry/Place Bound Top")
		(29 "B.CrtYd" user "Package Geometry/Place Bound Bottom")
		(35 "F.Fab" user "Ref Des/Assembly Top")
		(33 "B.Fab" user "Ref Des/Assembly Bottom")
	)
	(footprint ""
		(layer "F.Cu")
		(at 37.004752 -142.88897 180)
		(property "Reference" "R29"
			(at 0 0 180)
			(layer "F.SilkS")
			(hide yes)
			(effects
				(font
					(size 1.27 1.27)
				)
			)
		)
		(property "Value" ""
			(at 0 0 180)
			(layer "F.Fab")
			(effects
				(font
					(size 1.27 1.27)
				)
			)
		)
		(duplicate_pad_numbers_are_jumpers no)
		(fp_line
			(start 0.7874 0.4064)
			(end -0.7874 0.4064)
			(stroke
				(width 0.1524)
				(type default)
			)
			(layer "F.SilkS")
		)
		(fp_line
			(start 0.7874 -0.4064)
			(end 0.7874 0.4064)
			(stroke
				(width 0.1524)
				(type default)
			)
			(layer "F.SilkS")
		)
		(fp_line
			(start -0.7874 0.4064)
			(end -0.7874 -0.4064)
			(stroke
				(width 0.1524)
				(type default)
			)
			(layer "F.SilkS")
		)
		(fp_line
			(start -0.7874 -0.4064)
			(end 0.7874 -0.4064)
			(stroke
				(width 0.1524)
				(type default)
			)
			(layer "F.SilkS")
		)
		(fp_line
			(start 0.67945 0.3048)
			(end 0.120396 0.3048)
			(stroke
				(width 0.1)
				(type default)
			)
			(layer "F.Fab")
		)
		(fp_line
			(start 0.67945 -0.3048)
			(end 0.67945 0.3048)
			(stroke
				(width 0.1)
				(type default)
			)
			(layer "F.Fab")
		)
		(fp_line
			(start 0.12065 -0.2794)
			(end 0.12065 -0.3048)
			(stroke
				(width 0.1)
				(type default)
			)
			(layer "F.Fab")
		)
		(fp_line
			(start 0.12065 -0.3048)
			(end 0.67945 -0.3048)
			(stroke
				(width 0.1)
				(type default)
			)
			(layer "F.Fab")
		)
		(fp_line
			(start 0.120396 0.3048)
			(end 0.120396 0.2794)
			(stroke
				(width 0.1)
				(type default)
			)
			(layer "F.Fab")
		)
		(fp_line
			(start 0.120396 0.2794)
			(end -0.12065 0.2794)
			(stroke
				(width 0.1)
				(type default)
			)
			(layer "F.Fab")
		)
		(fp_line
			(start -0.12065 0.3048)
			(end -0.67945 0.3048)
			(stroke
				(width 0.1)
				(type default)
			)
			(layer "F.Fab")
		)
		(fp_line
			(start -0.12065 0.2794)
			(end -0.12065 0.3048)
			(stroke
				(width 0.1)
				(type default)
			)
			(layer "F.Fab")
		)
		(fp_line
			(start -0.12065 -0.2794)
			(end 0.12065 -0.2794)
			(stroke
				(width 0.1)
				(type default)
			)
			(layer "F.Fab")
		)
		(fp_line
			(start -0.12065 -0.305054)
			(end -0.12065 -0.2794)
			(stroke
				(width 0.1)
				(type default)
			)
			(layer "F.Fab")
		)
		(fp_line
			(start -0.67945 0.3048)
			(end -0.67945 -0.305054)
			(stroke
				(width 0.1)
				(type default)
			)
			(layer "F.Fab")
		)
		(fp_line
			(start -0.67945 -0.305054)
			(end -0.12065 -0.305054)
			(stroke
				(width 0.1)
				(type default)
			)
			(layer "F.Fab")
		)
		(pad "1" smd circle
			(at -0.40005 0 180)
			(size 0 0)
			(layers "F.Cu" "F.Mask" "F.Paste")
			(net "NIC0_BIF0_N")
		)
		(pad "2" smd circle
			(at 0.40005 0 180)
			(size 0 0)
			(layers "F.Cu" "F.Mask" "F.Paste")
			(net "P3V3_AUX")
		)
	)
	(footprint ""
		(layer "F.Cu")
		(at 223.844612 -254.18542 -90)
		(property "Reference" "C4285"
			(at 0 0 270)
			(layer "F.SilkS")
			(hide yes)
			(effects
				(font
					(size 1.27 1.27)
				)
			)
		)
		(property "Value" ""
			(at 0 0 270)
			(layer "F.Fab")
			(effects
				(font
					(size 1.27 1.27)
				)
			)
		)
		(duplicate_pad_numbers_are_jumpers no)
		(fp_line
			(start -1.2954 0.5842)
			(end -1.2954 -0.5842)
			(stroke
				(width 0.1524)
				(type default)
			)
			(layer "F.SilkS")
		)
		(fp_line
			(start 1.2954 0.5842)
			(end -1.2954 0.5842)
			(stroke
				(width 0.1524)
				(type default)
			)
			(layer "F.SilkS")
		)
		(fp_line
			(start -1.2954 -0.5842)
			(end 1.2954 -0.5842)
			(stroke
				(width 0.1524)
				(type default)
			)
			(layer "F.SilkS")
		)
		(fp_line
			(start 1.2954 -0.5842)
			(end 1.2954 0.5842)
			(stroke
				(width 0.1524)
				(type default)
			)
			(layer "F.SilkS")
		)
		(fp_line
			(start -0.8636 0.4572)
			(end -0.8636 0.4064)
			(stroke
				(width 0.1)
				(type default)
			)
			(layer "F.Fab")
		)
		(fp_line
			(start 0.8636 0.4572)
			(end -0.8636 0.4572)
			(stroke
				(width 0.1)
				(type default)
			)
			(layer "F.Fab")
		)
		(fp_line
			(start -1.1938 0.4064)
			(end -1.1938 -0.4064)
			(stroke
				(width 0.1)
				(type default)
			)
			(layer "F.Fab")
		)
		(fp_line
			(start -0.8636 0.4064)
			(end -1.1938 0.4064)
			(stroke
				(width 0.1)
				(type default)
			)
			(layer "F.Fab")
		)
		(fp_line
			(start 0.8636 0.4064)
			(end 0.8636 0.4572)
			(stroke
				(width 0.1)
				(type default)
			)
			(layer "F.Fab")
		)
		(fp_line
			(start 1.1938 0.4064)
			(end 0.8636 0.4064)
			(stroke
				(width 0.1)
				(type default)
			)
			(layer "F.Fab")
		)
		(fp_line
			(start -1.1938 -0.4064)
			(end -0.8636 -0.4064)
			(stroke
				(width 0.1)
				(type default)
			)
			(layer "F.Fab")
		)
		(fp_line
			(start -0.8636 -0.4064)
			(end -0.8636 -0.4572)
			(stroke
				(width 0.1)
				(type default)
			)
			(layer "F.Fab")
		)
		(fp_line
			(start 0.8636 -0.4064)
			(end 1.1938 -0.4064)
			(stroke
				(width 0.1)
				(type default)
			)
			(layer "F.Fab")
		)
		(fp_line
			(start 1.1938 -0.4064)
			(end 1.1938 0.4064)
			(stroke
				(width 0.1)
				(type default)
			)
			(layer "F.Fab")
		)
		(fp_line
			(start -0.8636 -0.4572)
			(end 0.8636 -0.4572)
			(stroke
				(width 0.1)
				(type default)
			)
			(layer "F.Fab")
		)
		(fp_line
			(start 0.8636 -0.4572)
			(end 0.8636 -0.4064)
			(stroke
				(width 0.1)
				(type default)
			)
			(layer "F.Fab")
		)
		(pad "1" smd rect
			(at -0.7366 0 180)
			(size 0.7112 0.8128)
			(layers "F.Cu" "F.Mask" "F.Paste")
			(net "P1V25_SERDES_VDDPLL_PEX1_C3")
		)
		(pad "2" smd rect
			(at 0.7366 0 180)
			(size 0.7112 0.8128)
			(layers "F.Cu" "F.Mask" "F.Paste")
			(net "GND")
		)
	)
	(footprint ""
		(layer "F.Cu")
		(at 269.750286 -250.070874 -90)
		(property "Reference" "R1346"
			(at 0 0 270)
			(layer "F.SilkS")
			(hide yes)
			(effects
				(font
					(size 1.27 1.27)
				)
			)
		)
		(property "Value" ""
			(at 0 0 270)
			(layer "F.Fab")
			(effects
				(font
					(size 1.27 1.27)
				)
			)
		)
		(duplicate_pad_numbers_are_jumpers no)
		(fp_line
			(start -0.7874 0.4064)
			(end -0.7874 -0.4064)
			(stroke
				(width 0.1524)
				(type default)
			)
			(layer "F.SilkS")
		)
		(fp_line
			(start 0.7874 0.4064)
			(end -0.7874 0.4064)
			(stroke
				(width 0.1524)
				(type default)
			)
			(layer "F.SilkS")
		)
		(fp_line
			(start -0.7874 -0.4064)
			(end 0.7874 -0.4064)
			(stroke
				(width 0.1524)
				(type default)
			)
			(layer "F.SilkS")
		)
		(fp_line
			(start 0.7874 -0.4064)
			(end 0.7874 0.4064)
			(stroke
				(width 0.1524)
				(type default)
			)
			(layer "F.SilkS")
		)
		(fp_line
			(start -0.67945 0.3048)
			(end -0.67945 -0.305054)
			(stroke
				(width 0.1)
				(type default)
			)
			(layer "F.Fab")
		)
		(fp_line
			(start -0.12065 0.3048)
			(end -0.67945 0.3048)
			(stroke
				(width 0.1)
				(type default)
			)
			(layer "F.Fab")
		)
		(fp_line
			(start 0.120396 0.3048)
			(end 0.120396 0.2794)
			(stroke
				(width 0.1)
				(type default)
			)
			(layer "F.Fab")
		)
		(fp_line
			(start 0.67945 0.3048)
			(end 0.120396 0.3048)
			(stroke
				(width 0.1)
				(type default)
			)
			(layer "F.Fab")
		)
		(fp_line
			(start -0.12065 0.2794)
			(end -0.12065 0.3048)
			(stroke
				(width 0.1)
				(type default)
			)
			(layer "F.Fab")
		)
		(fp_line
			(start 0.120396 0.2794)
			(end -0.12065 0.2794)
			(stroke
				(width 0.1)
				(type default)
			)
			(layer "F.Fab")
		)
		(fp_line
			(start -0.12065 -0.2794)
			(end 0.12065 -0.2794)
			(stroke
				(width 0.1)
				(type default)
			)
			(layer "F.Fab")
		)
		(fp_line
			(start 0.12065 -0.2794)
			(end 0.12065 -0.3048)
			(stroke
				(width 0.1)
				(type default)
			)
			(layer "F.Fab")
		)
		(fp_line
			(start 0.12065 -0.3048)
			(end 0.67945 -0.3048)
			(stroke
				(width 0.1)
				(type default)
			)
			(layer "F.Fab")
		)
		(fp_line
			(start 0.67945 -0.3048)
			(end 0.67945 0.3048)
			(stroke
				(width 0.1)
				(type default)
			)
			(layer "F.Fab")
		)
		(fp_line
			(start -0.67945 -0.305054)
			(end -0.12065 -0.305054)
			(stroke
				(width 0.1)
				(type default)
			)
			(layer "F.Fab")
		)
		(fp_line
			(start -0.12065 -0.305054)
			(end -0.12065 -0.2794)
			(stroke
				(width 0.1)
				(type default)
			)
			(layer "F.Fab")
		)
		(pad "1" smd circle
			(at -0.40005 0 270)
			(size 0 0)
			(layers "F.Cu" "F.Mask" "F.Paste")
			(net "PEX2_MODE_SEL10")
		)
		(pad "2" smd circle
			(at 0.40005 0 270)
			(size 0 0)
			(layers "F.Cu" "F.Mask" "F.Paste")
			(net "P1V8_PEX")
		)
	)
	(footprint ""
		(layer "F.Cu")
		(at 319.206626 -294.77335 90)
		(property "Reference" "U427"
			(at -1.0922 -2.174748 90)
			(unlocked yes)
			(layer "F.SilkS")
			(effects
				(font
					(size 0.7874 0.5842)
					(thickness 0.1524)
				)
				(justify left)
			)
		)
		(property "Value" ""
			(at 0 0 90)
			(layer "F.Fab")
			(effects
				(font
					(size 1.27 1.27)
				)
			)
		)
		(duplicate_pad_numbers_are_jumpers no)
		(fp_line
			(start 1.0414 -1.575054)
			(end 1.0414 1.575054)
			(stroke
				(width 0.1524)
				(type default)
			)
			(layer "F.SilkS")
		)
		(fp_line
			(start 0.254 -1.575054)
			(end 1.0414 -1.575054)
			(stroke
				(width 0.1524)
				(type default)
			)
			(layer "F.SilkS")
		)
		(fp_line
			(start 0.2286 -1.575054)
			(end 0 -1.272032)
			(stroke
				(width 0.1524)
				(type default)
			)
			(layer "F.SilkS")
		)
		(fp_line
			(start -1.0414 -1.575054)
			(end -0.254 -1.575054)
			(stroke
				(width 0.1524)
				(type default)
			)
			(layer "F.SilkS")
		)
		(fp_line
			(start 0 -1.272032)
			(end -0.254 -1.575054)
			(stroke
				(width 0.1524)
				(type default)
			)
			(layer "F.SilkS")
		)
		(fp_line
			(start 1.0414 1.575054)
			(end -1.0414 1.575054)
			(stroke
				(width 0.1524)
				(type default)
			)
			(layer "F.SilkS")
		)
		(fp_line
			(start -1.0414 1.575054)
			(end -1.0414 -1.575054)
			(stroke
				(width 0.1524)
				(type default)
			)
			(layer "F.SilkS")
		)
		(fp_poly
			(pts
				(xy -2.710688 -0.975106) (xy -3.726688 -1.483106) (xy -3.726688 -0.467106)
			)
			(stroke
				(width 0)
				(type default)
			)
			(fill yes)
			(layer "F.SilkS")
		)
		(fp_line
			(start 1.4478 -1.5748)
			(end 1.4478 -1.2192)
			(stroke
				(width 0.1)
				(type default)
			)
			(layer "F.Fab")
		)
		(fp_line
			(start -1.4478 -1.5748)
			(end 1.4478 -1.5748)
			(stroke
				(width 0.1)
				(type default)
			)
			(layer "F.Fab")
		)
		(fp_line
			(start 2.5654 -1.2192)
			(end 2.5654 1.2192)
			(stroke
				(width 0.1)
				(type default)
			)
			(layer "F.Fab")
		)
		(fp_line
			(start 1.4478 -1.2192)
			(end 2.5654 -1.2192)
			(stroke
				(width 0.1)
				(type default)
			)
			(layer "F.Fab")
		)
		(fp_line
			(start -1.4478 -1.2192)
			(end -1.4478 -1.5748)
			(stroke
				(width 0.1)
				(type default)
			)
			(layer "F.Fab")
		)
		(fp_line
			(start -2.5654 -1.2192)
			(end -1.4478 -1.2192)
			(stroke
				(width 0.1)
				(type default)
			)
			(layer "F.Fab")
		)
		(fp_line
			(start 2.5654 1.2192)
			(end 1.4478 1.2192)
			(stroke
				(width 0.1)
				(type default)
			)
			(layer "F.Fab")
		)
		(fp_line
			(start 1.4478 1.2192)
			(end 1.4478 1.5748)
			(stroke
				(width 0.1)
				(type default)
			)
			(layer "F.Fab")
		)
		(fp_line
			(start -1.4478 1.2192)
			(end -2.5654 1.2192)
			(stroke
				(width 0.1)
				(type default)
			)
			(layer "F.Fab")
		)
		(fp_line
			(start -2.5654 1.2192)
			(end -2.5654 -1.2192)
			(stroke
				(width 0.1)
				(type default)
			)
			(layer "F.Fab")
		)
		(fp_line
			(start 1.4478 1.5748)
			(end -1.4478 1.5748)
			(stroke
				(width 0.1)
				(type default)
			)
			(layer "F.Fab")
		)
		(fp_line
			(start -1.4478 1.5748)
			(end -1.4478 1.2192)
			(stroke
				(width 0.1)
				(type default)
			)
			(layer "F.Fab")
		)
		(fp_poly
			(pts
				(xy -2.710688 -0.975106) (xy -3.726688 -1.483106) (xy -3.726688 -0.467106)
			)
			(stroke
				(width 0)
				(type default)
			)
			(fill yes)
			(layer "F.Fab")
		)
		(pad "1" smd rect
			(at -1.849882 -0.975106)
			(size 0.3556 1.3208)
			(layers "F.Cu" "F.Mask" "F.Paste")
			(net "RST_PEX2_PERST_R_N")
		)
		(pad "2" smd rect
			(at -1.849882 -0.32512)
			(size 0.3556 1.3208)
			(layers "F.Cu" "F.Mask" "F.Paste")
			(net "RST_PEX2_S0_PERST_N")
		)
		(pad "3" smd rect
			(at -1.849882 0.32512)
			(size 0.3556 1.3208)
			(layers "F.Cu" "F.Mask" "F.Paste")
			(net "RST_PEX2_PERST_R_N")
		)
		(pad "4" smd rect
			(at -1.849882 0.975106)
			(size 0.3556 1.3208)
			(layers "F.Cu" "F.Mask" "F.Paste")
			(net "GND")
		)
		(pad "5" smd rect
			(at 1.849882 0.975106)
			(size 0.3556 1.3208)
			(layers "F.Cu" "F.Mask" "F.Paste")
			(net "RST_PEX2_S1_PERST_N")
		)
		(pad "6" smd rect
			(at 1.849882 0.32512)
			(size 0.3556 1.3208)
			(layers "F.Cu" "F.Mask" "F.Paste")
			(net "RST_PEX2_PERST_R_N")
		)
		(pad "7" smd rect
			(at 1.849882 -0.32512)
			(size 0.3556 1.3208)
			(layers "F.Cu" "F.Mask" "F.Paste")
			(net "RST_PEX2_S3_PERST_N")
		)
		(pad "8" smd rect
			(at 1.849882 -0.975106)
			(size 0.3556 1.3208)
			(layers "F.Cu" "F.Mask" "F.Paste")
			(net "P1V8_PEX")
		)
	)
	(footprint ""
		(layer "F.Cu")
		(at 136.250172 -276.010116)
		(property "Reference" "H135"
			(at -0.550672 -4.599432 0)
			(unlocked yes)
			(layer "F.SilkS")
			(effects
				(font
					(size 0.7874 0.5842)
					(thickness 0.1524)
				)
				(justify left)
			)
		)
		(property "Value" ""
			(at 0 0 0)
			(layer "F.Fab")
			(effects
				(font
					(size 1.27 1.27)
				)
			)
		)
		(duplicate_pad_numbers_are_jumpers no)
		(pad "1" thru_hole circle
			(at 0 0)
			(size 6.5024 6.5024)
			(drill 3.2004)
			(layers "*.Cu" "*.Mask")
			(remove_unused_layers no)
			(net "GND")
			(clearance -1.397)
		)
	)
	(footprint ""
		(layer "F.Cu")
		(at 222.492316 -257.975862 -90)
		(property "Reference" "R6492"
			(at 0 0 270)
			(layer "F.SilkS")
			(hide yes)
			(effects
				(font
					(size 1.27 1.27)
				)
			)
		)
		(property "Value" ""
			(at 0 0 270)
			(layer "F.Fab")
			(effects
				(font
					(size 1.27 1.27)
				)
			)
		)
		(duplicate_pad_numbers_are_jumpers no)
		(fp_line
			(start -0.7874 0.4064)
			(end -0.7874 -0.4064)
			(stroke
				(width 0.1524)
				(type default)
			)
			(layer "F.SilkS")
		)
		(fp_line
			(start 0.7874 0.4064)
			(end -0.7874 0.4064)
			(stroke
				(width 0.1524)
				(type default)
			)
			(layer "F.SilkS")
		)
		(fp_line
			(start -0.7874 -0.4064)
			(end 0.7874 -0.4064)
			(stroke
				(width 0.1524)
				(type default)
			)
			(layer "F.SilkS")
		)
		(fp_line
			(start 0.7874 -0.4064)
			(end 0.7874 0.4064)
			(stroke
				(width 0.1524)
				(type default)
			)
			(layer "F.SilkS")
		)
		(fp_line
			(start -0.67945 0.3048)
			(end -0.67945 -0.305054)
			(stroke
				(width 0.1)
				(type default)
			)
			(layer "F.Fab")
		)
		(fp_line
			(start -0.12065 0.3048)
			(end -0.67945 0.3048)
			(stroke
				(width 0.1)
				(type default)
			)
			(layer "F.Fab")
		)
		(fp_line
			(start 0.120396 0.3048)
			(end 0.120396 0.2794)
			(stroke
				(width 0.1)
				(type default)
			)
			(layer "F.Fab")
		)
		(fp_line
			(start 0.67945 0.3048)
			(end 0.120396 0.3048)
			(stroke
				(width 0.1)
				(type default)
			)
			(layer "F.Fab")
		)
		(fp_line
			(start -0.12065 0.2794)
			(end -0.12065 0.3048)
			(stroke
				(width 0.1)
				(type default)
			)
			(layer "F.Fab")
		)
		(fp_line
			(start 0.120396 0.2794)
			(end -0.12065 0.2794)
			(stroke
				(width 0.1)
				(type default)
			)
			(layer "F.Fab")
		)
		(fp_line
			(start -0.12065 -0.2794)
			(end 0.12065 -0.2794)
			(stroke
				(width 0.1)
				(type default)
			)
			(layer "F.Fab")
		)
		(fp_line
			(start 0.12065 -0.2794)
			(end 0.12065 -0.3048)
			(stroke
				(width 0.1)
				(type default)
			)
			(layer "F.Fab")
		)
		(fp_line
			(start 0.12065 -0.3048)
			(end 0.67945 -0.3048)
			(stroke
				(width 0.1)
				(type default)
			)
			(layer "F.Fab")
		)
		(fp_line
			(start 0.67945 -0.3048)
			(end 0.67945 0.3048)
			(stroke
				(width 0.1)
				(type default)
			)
			(layer "F.Fab")
		)
		(fp_line
			(start -0.67945 -0.305054)
			(end -0.12065 -0.305054)
			(stroke
				(width 0.1)
				(type default)
			)
			(layer "F.Fab")
		)
		(fp_line
			(start -0.12065 -0.305054)
			(end -0.12065 -0.2794)
			(stroke
				(width 0.1)
				(type default)
			)
			(layer "F.Fab")
		)
		(pad "1" smd circle
			(at -0.40005 0 270)
			(size 0 0)
			(layers "F.Cu" "F.Mask" "F.Paste")
			(net "P1V25_SERDES_VDDPLL_PEX1")
		)
		(pad "2" smd circle
			(at 0.40005 0 270)
			(size 0 0)
			(layers "F.Cu" "F.Mask" "F.Paste")
			(net "P1V25_SERDES_VDDPLL_PEX1_C1")
		)
	)
)
